# S9S_MB_2U (Grand Teton) — schematic netlist excerpt (pin names and nets, part order shuffled) for the footprints in the layout excerpt that follows; sources: Cadence DE-HDL packaged netlist, KiCad conversion of 03242023_DA0F0TMBIJ0_F0T_Motherboard_J_brd_V01_OCP.brd

R1662  Q_RES  33.2 1% CHIP  pkg 0402LF  page 241 : A = SMB_VR_3V3AUX_SDA ; B = SMB_VR_3V3AUX_SDA_R
R3868  Q_RES  0 5% EMPTY  pkg 0402LF  page 162 : A = P12V_OCP_SENSE_2 ; B = P12V_OCP_V3_2_ISENSE_MAM_TIC

(kicad_pcb
	(version 20260206)
	(generator "pcbnew")
	(generator_version "10.0")
	(general
		(thickness 1.6)
		(legacy_teardrops no)
	)
	(paper "A4")
	(title_block
		(title "03242023_DA0F0TMBIJ0_F0T_Motherboard_J_brd_V01_OCP.brd")
		(comment 1 "Grand Teton / footprints 317-318 of 6105")
	)
	(layers
		(0 "F.Cu" signal "TOP")
		(4 "In1.Cu" signal "GND")
		(6 "In2.Cu" signal "IN1")
		(8 "In3.Cu" signal "GND1")
		(10 "In4.Cu" signal "IN2")
		(12 "In5.Cu" signal "GND2")
		(14 "In6.Cu" signal "IN3")
		(16 "In7.Cu" signal "GND3")
		(18 "In8.Cu" signal "VCC")
		(20 "In9.Cu" signal "VCC1")
		(22 "In10.Cu" signal "GND4")
		(24 "In11.Cu" signal "IN4")
		(26 "In12.Cu" signal "GND5")
		(28 "In13.Cu" signal "IN5")
		(30 "In14.Cu" signal "GND6")
		(32 "In15.Cu" signal "IN6")
		(34 "In16.Cu" signal "GND7")
		(2 "B.Cu" signal "BOTTOM")
		(9 "F.Adhes" user "F.Adhesive")
		(11 "B.Adhes" user "B.Adhesive")
		(13 "F.Paste" user "Package Geometry/Pastemask Top")
		(15 "B.Paste" user "Package Geometry/Pastemask Bottom")
		(5 "F.SilkS" user "Ref Des/Silkscreen Top")
		(7 "B.SilkS" user "Ref Des/Silkscreen Bottom")
		(1 "F.Mask" user "Board Geometry/Soldermask Top")
		(3 "B.Mask" user "Board Geometry/Soldermask Bottom")
		(17 "Dwgs.User" user "User.Drawings")
		(19 "Cmts.User" user "User.Comments")
		(21 "Eco1.User" user "User.Eco1")
		(23 "Eco2.User" user "User.Eco2")
		(25 "Edge.Cuts" user "Board Geometry/Outline")
		(27 "Margin" user)
		(31 "F.CrtYd" user "Package Geometry/Place Bound Top")
		(29 "B.CrtYd" user "Package Geometry/Place Bound Bottom")
		(35 "F.Fab" user "Ref Des/Assembly Top")
		(33 "B.Fab" user "Ref Des/Assembly Bottom")
	)
	(footprint ""
		(layer "F.Cu")
		(at 31.53918 -122.380502 90)
		(property "Reference" "R1662"
			(at 0 0 90)
			(layer "F.SilkS")
			(hide yes)
			(effects
				(font
					(size 1.27 1.27)
				)
			)
		)
		(property "Value" ""
			(at 0 0 90)
			(layer "F.Fab")
			(effects
				(font
					(size 1.27 1.27)
				)
			)
		)
		(duplicate_pad_numbers_are_jumpers no)
		(fp_line
			(start 0.7874 -0.4064)
			(end 0.7874 0.4064)
			(stroke
				(width 0.1524)
				(type default)
			)
			(layer "F.SilkS")
		)
		(fp_line
			(start -0.7874 -0.4064)
			(end 0.7874 -0.4064)
			(stroke
				(width 0.1524)
				(type default)
			)
			(layer "F.SilkS")
		)
		(fp_line
			(start 0.7874 0.4064)
			(end -0.7874 0.4064)
			(stroke
				(width 0.1524)
				(type default)
			)
			(layer "F.SilkS")
		)
		(fp_line
			(start -0.7874 0.4064)
			(end -0.7874 -0.4064)
			(stroke
				(width 0.1524)
				(type default)
			)
			(layer "F.SilkS")
		)
		(fp_line
			(start -0.12065 -0.305054)
			(end -0.12065 -0.2794)
			(stroke
				(width 0.1)
				(type default)
			)
			(layer "F.Fab")
		)
		(fp_line
			(start -0.67945 -0.305054)
			(end -0.12065 -0.305054)
			(stroke
				(width 0.1)
				(type default)
			)
			(layer "F.Fab")
		)
		(fp_line
			(start 0.67945 -0.3048)
			(end 0.67945 0.3048)
			(stroke
				(width 0.1)
				(type default)
			)
			(layer "F.Fab")
		)
		(fp_line
			(start 0.12065 -0.3048)
			(end 0.67945 -0.3048)
			(stroke
				(width 0.1)
				(type default)
			)
			(layer "F.Fab")
		)
		(fp_line
			(start 0.12065 -0.2794)
			(end 0.12065 -0.3048)
			(stroke
				(width 0.1)
				(type default)
			)
			(layer "F.Fab")
		)
		(fp_line
			(start -0.12065 -0.2794)
			(end 0.12065 -0.2794)
			(stroke
				(width 0.1)
				(type default)
			)
			(layer "F.Fab")
		)
		(fp_line
			(start 0.120396 0.2794)
			(end -0.12065 0.2794)
			(stroke
				(width 0.1)
				(type default)
			)
			(layer "F.Fab")
		)
		(fp_line
			(start -0.12065 0.2794)
			(end -0.12065 0.3048)
			(stroke
				(width 0.1)
				(type default)
			)
			(layer "F.Fab")
		)
		(fp_line
			(start 0.67945 0.3048)
			(end 0.120396 0.3048)
			(stroke
				(width 0.1)
				(type default)
			)
			(layer "F.Fab")
		)
		(fp_line
			(start 0.120396 0.3048)
			(end 0.120396 0.2794)
			(stroke
				(width 0.1)
				(type default)
			)
			(layer "F.Fab")
		)
		(fp_line
			(start -0.12065 0.3048)
			(end -0.67945 0.3048)
			(stroke
				(width 0.1)
				(type default)
			)
			(layer "F.Fab")
		)
		(fp_line
			(start -0.67945 0.3048)
			(end -0.67945 -0.305054)
			(stroke
				(width 0.1)
				(type default)
			)
			(layer "F.Fab")
		)
		(pad "1" smd circle
			(at -0.40005 0 90)
			(size 0 0)
			(layers "F.Cu" "F.Mask" "F.Paste")
			(net "SMB_VR_3V3AUX_SDA")
		)
		(pad "2" smd circle
			(at 0.40005 0 90)
			(size 0 0)
			(layers "F.Cu" "F.Mask" "F.Paste")
			(net "SMB_VR_3V3AUX_SDA_R")
		)
	)
	(footprint ""
		(layer "F.Cu")
		(at 60.127388 -32.287972 180)
		(property "Reference" "R3868"
			(at 0 0 180)
			(layer "F.SilkS")
			(hide yes)
			(effects
				(font
					(size 1.27 1.27)
				)
			)
		)
		(property "Value" ""
			(at 0 0 180)
			(layer "F.Fab")
			(effects
				(font
					(size 1.27 1.27)
				)
			)
		)
		(duplicate_pad_numbers_are_jumpers no)
		(fp_line
			(start 0.7874 0.4064)
			(end -0.7874 0.4064)
			(stroke
				(width 0.1524)
				(type default)
			)
			(layer "F.SilkS")
		)
		(fp_line
			(start 0.7874 -0.4064)
			(end 0.7874 0.4064)
			(stroke
				(width 0.1524)
				(type default)
			)
			(layer "F.SilkS")
		)
		(fp_line
			(start -0.7874 0.4064)
			(end -0.7874 -0.4064)
			(stroke
				(width 0.1524)
				(type default)
			)
			(layer "F.SilkS")
		)
		(fp_line
			(start -0.7874 -0.4064)
			(end 0.7874 -0.4064)
			(stroke
				(width 0.1524)
				(type default)
			)
			(layer "F.SilkS")
		)
		(fp_line
			(start 0.67945 0.3048)
			(end 0.120396 0.3048)
			(stroke
				(width 0.1)
				(type default)
			)
			(layer "F.Fab")
		)
		(fp_line
			(start 0.67945 -0.3048)
			(end 0.67945 0.3048)
			(stroke
				(width 0.1)
				(type default)
			)
			(layer "F.Fab")
		)
		(fp_line
			(start 0.12065 -0.2794)
			(end 0.12065 -0.3048)
			(stroke
				(width 0.1)
				(type default)
			)
			(layer "F.Fab")
		)
		(fp_line
			(start 0.12065 -0.3048)
			(end 0.67945 -0.3048)
			(stroke
				(width 0.1)
				(type default)
			)
			(layer "F.Fab")
		)
		(fp_line
			(start 0.120396 0.3048)
			(end 0.120396 0.2794)
			(stroke
				(width 0.1)
				(type default)
			)
			(layer "F.Fab")
		)
		(fp_line
			(start 0.120396 0.2794)
			(end -0.12065 0.2794)
			(stroke
				(width 0.1)
				(type default)
			)
			(layer "F.Fab")
		)
		(fp_line
			(start -0.12065 0.3048)
			(end -0.67945 0.3048)
			(stroke
				(width 0.1)
				(type default)
			)
			(layer "F.Fab")
		)
		(fp_line
			(start -0.12065 0.2794)
			(end -0.12065 0.3048)
			(stroke
				(width 0.1)
				(type default)
			)
			(layer "F.Fab")
		)
		(fp_line
			(start -0.12065 -0.2794)
			(end 0.12065 -0.2794)
			(stroke
				(width 0.1)
				(type default)
			)
			(layer "F.Fab")
		)
		(fp_line
			(start -0.12065 -0.305054)
			(end -0.12065 -0.2794)
			(stroke
				(width 0.1)
				(type default)
			)
			(layer "F.Fab")
		)
		(fp_line
			(start -0.67945 0.3048)
			(end -0.67945 -0.305054)
			(stroke
				(width 0.1)
				(type default)
			)
			(layer "F.Fab")
		)
		(fp_line
			(start -0.67945 -0.305054)
			(end -0.12065 -0.305054)
			(stroke
				(width 0.1)
				(type default)
			)
			(layer "F.Fab")
		)
		(pad "1" smd rect
			(at -0.40005 0)
			(size 0.4572 0.508)
			(layers "F.Cu" "F.Mask" "F.Paste")
			(net "P12V_OCP_SENSE_2")
		)
		(pad "2" smd rect
			(at 0.40005 0)
			(size 0.4572 0.508)
			(layers "F.Cu" "F.Mask" "F.Paste")
			(net "P12V_OCP_V3_2_ISENSE_MAM_TIC")
		)
	)
)
